(kicad_pcb
	(version 20260206)
	(generator "pcbnew")
	(generator_version "10.0")
	(general
		(thickness 1.6)
		(legacy_teardrops no)
	)
	(paper "A4")
	(title_block
		(title "01162023_DA0F0TEBIF0_F0T_Expander_BD_F_brd_V02_OCP.brd")
		(comment 1 "Grand Teton / footprints 4743-4749 of 9728")
	)
	(layers
		(0 "F.Cu" signal "TOP")
		(4 "In1.Cu" signal "GND")
		(6 "In2.Cu" signal "VCC")
		(8 "In3.Cu" signal "VCC1")
		(10 "In4.Cu" signal "GND1")
		(12 "In5.Cu" signal "IN1")
		(14 "In6.Cu" signal "GND2")
		(16 "In7.Cu" signal "IN2")
		(18 "In8.Cu" signal "GND3")
		(20 "In9.Cu" signal "IN3")
		(22 "In10.Cu" signal "GND4")
		(24 "In11.Cu" signal "IN4")
		(26 "In12.Cu" signal "GND5")
		(28 "In13.Cu" signal "IN5")
		(30 "In14.Cu" signal "GND6")
		(32 "In15.Cu" signal "IN6")
		(34 "In16.Cu" signal "GND7")
		(2 "B.Cu" signal "BOTTOM")
		(9 "F.Adhes" user "F.Adhesive")
		(11 "B.Adhes" user "B.Adhesive")
		(13 "F.Paste" user "Package Geometry/Pastemask Top")
		(15 "B.Paste" user "Package Geometry/Pastemask Bottom")
		(5 "F.SilkS" user "Ref Des/Silkscreen Top")
		(7 "B.SilkS" user "Ref Des/Silkscreen Bottom")
		(1 "F.Mask" user "Board Geometry/Soldermask Top")
		(3 "B.Mask" user "Board Geometry/Soldermask Bottom")
		(17 "Dwgs.User" user "User.Drawings")
		(19 "Cmts.User" user "User.Comments")
		(21 "Eco1.User" user "User.Eco1")
		(23 "Eco2.User" user "User.Eco2")
		(25 "Edge.Cuts" user "Board Geometry/Outline")
		(27 "Margin" user)
		(31 "F.CrtYd" user "Package Geometry/Place Bound Top")
		(29 "B.CrtYd" user "Package Geometry/Place Bound Bottom")
		(35 "F.Fab" user "Ref Des/Assembly Top")
		(33 "B.Fab" user "Ref Des/Assembly Bottom")
	)
	(footprint ""
		(layer "F.Cu")
		(at 112.311942 -113.563654)
		(property "Reference" "PC613"
			(at 0 0 0)
			(layer "F.SilkS")
			(hide yes)
			(effects
				(font
					(size 1.27 1.27)
				)
			)
		)
		(property "Value" ""
			(at 0 0 0)
			(layer "F.Fab")
			(effects
				(font
					(size 1.27 1.27)
				)
			)
		)
		(duplicate_pad_numbers_are_jumpers no)
		(fp_line
			(start -0.7874 -0.4064)
			(end 0.7874 -0.4064)
			(stroke
				(width 0.1524)
				(type default)
			)
			(layer "F.SilkS")
		)
		(fp_line
			(start -0.7874 0.4064)
			(end -0.7874 -0.4064)
			(stroke
				(width 0.1524)
				(type default)
			)
			(layer "F.SilkS")
		)
		(fp_line
			(start 0.7874 -0.4064)
			(end 0.7874 0.4064)
			(stroke
				(width 0.1524)
				(type default)
			)
			(layer "F.SilkS")
		)
		(fp_line
			(start 0.7874 0.4064)
			(end -0.7874 0.4064)
			(stroke
				(width 0.1524)
				(type default)
			)
			(layer "F.SilkS")
		)
		(fp_line
			(start -0.67945 -0.305054)
			(end -0.12065 -0.305054)
			(stroke
				(width 0.1)
				(type default)
			)
			(layer "F.Fab")
		)
		(fp_line
			(start -0.67945 0.3048)
			(end -0.67945 -0.305054)
			(stroke
				(width 0.1)
				(type default)
			)
			(layer "F.Fab")
		)
		(fp_line
			(start -0.12065 -0.305054)
			(end -0.12065 -0.2794)
			(stroke
				(width 0.1)
				(type default)
			)
			(layer "F.Fab")
		)
		(fp_line
			(start -0.12065 -0.2794)
			(end 0.12065 -0.2794)
			(stroke
				(width 0.1)
				(type default)
			)
			(layer "F.Fab")
		)
		(fp_line
			(start -0.12065 0.2794)
			(end -0.12065 0.3048)
			(stroke
				(width 0.1)
				(type default)
			)
			(layer "F.Fab")
		)
		(fp_line
			(start -0.12065 0.3048)
			(end -0.67945 0.3048)
			(stroke
				(width 0.1)
				(type default)
			)
			(layer "F.Fab")
		)
		(fp_line
			(start 0.120396 0.2794)
			(end -0.12065 0.2794)
			(stroke
				(width 0.1)
				(type default)
			)
			(layer "F.Fab")
		)
		(fp_line
			(start 0.120396 0.3048)
			(end 0.120396 0.2794)
			(stroke
				(width 0.1)
				(type default)
			)
			(layer "F.Fab")
		)
		(fp_line
			(start 0.12065 -0.3048)
			(end 0.67945 -0.3048)
			(stroke
				(width 0.1)
				(type default)
			)
			(layer "F.Fab")
		)
		(fp_line
			(start 0.12065 -0.2794)
			(end 0.12065 -0.3048)
			(stroke
				(width 0.1)
				(type default)
			)
			(layer "F.Fab")
		)
		(fp_line
			(start 0.67945 -0.3048)
			(end 0.67945 0.3048)
			(stroke
				(width 0.1)
				(type default)
			)
			(layer "F.Fab")
		)
		(fp_line
			(start 0.67945 0.3048)
			(end 0.120396 0.3048)
			(stroke
				(width 0.1)
				(type default)
			)
			(layer "F.Fab")
		)
		(pad "1" smd circle
			(at -0.40005 0)
			(size 0 0)
			(layers "F.Cu" "F.Mask" "F.Paste")
			(net "P12V_NIC1_CO_SS")
		)
		(pad "2" smd circle
			(at 0.40005 0)
			(size 0 0)
			(layers "F.Cu" "F.Mask" "F.Paste")
			(net "GND")
		)
	)
	(footprint ""
		(layer "F.Cu")
		(at 466.308948 -538.74416 180)
		(property "Reference" "J45_OTH"
			(at -3.2385 -1.402334 0)
			(unlocked yes)
			(layer "B.SilkS")
			(effects
				(font
					(size 0.7874 0.5842)
					(thickness 0.1524)
				)
				(justify mirror)
			)
		)
		(property "Value" ""
			(at 0 0 180)
			(layer "F.Fab")
			(effects
				(font
					(size 1.27 1.27)
				)
			)
		)
		(duplicate_pad_numbers_are_jumpers no)
		(pad "1" thru_hole circle
			(at 0 0 180)
			(size 0.4572 0.4572)
			(drill 0.2032)
			(layers "*.Cu" "*.Mask")
			(remove_unused_layers no)
			(net "Net_9091")
			(clearance 0.127)
			(thermal_gap 0.127)
			(padstack
				(mode front_inner_back)
				(layer "Inner"
					(shape circle)
					(size 0.4572 0.4572)
					(clearance 0.127)
				)
				(layer "B.Cu"
					(shape circle)
					(size 0.508 0.508)
					(clearance 0.1016)
				)
			)
		)
	)
	(footprint ""
		(layer "F.Cu")
		(at 194.367912 -52.035456 180)
		(property "Reference" "R866"
			(at 0 0 180)
			(layer "F.SilkS")
			(hide yes)
			(effects
				(font
					(size 1.27 1.27)
				)
			)
		)
		(property "Value" ""
			(at 0 0 180)
			(layer "F.Fab")
			(effects
				(font
					(size 1.27 1.27)
				)
			)
		)
		(duplicate_pad_numbers_are_jumpers no)
		(fp_line
			(start 0.7874 0.4064)
			(end -0.7874 0.4064)
			(stroke
				(width 0.1524)
				(type default)
			)
			(layer "F.SilkS")
		)
		(fp_line
			(start 0.7874 -0.4064)
			(end 0.7874 0.4064)
			(stroke
				(width 0.1524)
				(type default)
			)
			(layer "F.SilkS")
		)
		(fp_line
			(start -0.7874 0.4064)
			(end -0.7874 -0.4064)
			(stroke
				(width 0.1524)
				(type default)
			)
			(layer "F.SilkS")
		)
		(fp_line
			(start -0.7874 -0.4064)
			(end 0.7874 -0.4064)
			(stroke
				(width 0.1524)
				(type default)
			)
			(layer "F.SilkS")
		)
		(fp_line
			(start 0.67945 0.3048)
			(end 0.120396 0.3048)
			(stroke
				(width 0.1)
				(type default)
			)
			(layer "F.Fab")
		)
		(fp_line
			(start 0.67945 -0.3048)
			(end 0.67945 0.3048)
			(stroke
				(width 0.1)
				(type default)
			)
			(layer "F.Fab")
		)
		(fp_line
			(start 0.12065 -0.2794)
			(end 0.12065 -0.3048)
			(stroke
				(width 0.1)
				(type default)
			)
			(layer "F.Fab")
		)
		(fp_line
			(start 0.12065 -0.3048)
			(end 0.67945 -0.3048)
			(stroke
				(width 0.1)
				(type default)
			)
			(layer "F.Fab")
		)
		(fp_line
			(start 0.120396 0.3048)
			(end 0.120396 0.2794)
			(stroke
				(width 0.1)
				(type default)
			)
			(layer "F.Fab")
		)
		(fp_line
			(start 0.120396 0.2794)
			(end -0.12065 0.2794)
			(stroke
				(width 0.1)
				(type default)
			)
			(layer "F.Fab")
		)
		(fp_line
			(start -0.12065 0.3048)
			(end -0.67945 0.3048)
			(stroke
				(width 0.1)
				(type default)
			)
			(layer "F.Fab")
		)
		(fp_line
			(start -0.12065 0.2794)
			(end -0.12065 0.3048)
			(stroke
				(width 0.1)
				(type default)
			)
			(layer "F.Fab")
		)
		(fp_line
			(start -0.12065 -0.2794)
			(end 0.12065 -0.2794)
			(stroke
				(width 0.1)
				(type default)
			)
			(layer "F.Fab")
		)
		(fp_line
			(start -0.12065 -0.305054)
			(end -0.12065 -0.2794)
			(stroke
				(width 0.1)
				(type default)
			)
			(layer "F.Fab")
		)
		(fp_line
			(start -0.67945 0.3048)
			(end -0.67945 -0.305054)
			(stroke
				(width 0.1)
				(type default)
			)
			(layer "F.Fab")
		)
		(fp_line
			(start -0.67945 -0.305054)
			(end -0.12065 -0.305054)
			(stroke
				(width 0.1)
				(type default)
			)
			(layer "F.Fab")
		)
		(pad "1" smd circle
			(at -0.40005 0 180)
			(size 0 0)
			(layers "F.Cu" "F.Mask" "F.Paste")
			(net "P3V3_AUX")
		)
		(pad "2" smd circle
			(at 0.40005 0 180)
			(size 0 0)
			(layers "F.Cu" "F.Mask" "F.Paste")
			(net "PWRGD_P12V_SSD6")
		)
	)
	(footprint ""
		(layer "F.Cu")
		(at 123.67514 -93.748606)
		(property "Reference" "R1581"
			(at 0 0 0)
			(layer "F.SilkS")
			(hide yes)
			(effects
				(font
					(size 1.27 1.27)
				)
			)
		)
		(property "Value" ""
			(at 0 0 0)
			(layer "F.Fab")
			(effects
				(font
					(size 1.27 1.27)
				)
			)
		)
		(duplicate_pad_numbers_are_jumpers no)
		(fp_line
			(start -0.7874 -0.4064)
			(end 0.7874 -0.4064)
			(stroke
				(width 0.1524)
				(type default)
			)
			(layer "F.SilkS")
		)
		(fp_line
			(start -0.7874 0.4064)
			(end -0.7874 -0.4064)
			(stroke
				(width 0.1524)
				(type default)
			)
			(layer "F.SilkS")
		)
		(fp_line
			(start 0.7874 -0.4064)
			(end 0.7874 0.4064)
			(stroke
				(width 0.1524)
				(type default)
			)
			(layer "F.SilkS")
		)
		(fp_line
			(start 0.7874 0.4064)
			(end -0.7874 0.4064)
			(stroke
				(width 0.1524)
				(type default)
			)
			(layer "F.SilkS")
		)
		(fp_line
			(start -0.67945 -0.305054)
			(end -0.12065 -0.305054)
			(stroke
				(width 0.1)
				(type default)
			)
			(layer "F.Fab")
		)
		(fp_line
			(start -0.67945 0.3048)
			(end -0.67945 -0.305054)
			(stroke
				(width 0.1)
				(type default)
			)
			(layer "F.Fab")
		)
		(fp_line
			(start -0.12065 -0.305054)
			(end -0.12065 -0.2794)
			(stroke
				(width 0.1)
				(type default)
			)
			(layer "F.Fab")
		)
		(fp_line
			(start -0.12065 -0.2794)
			(end 0.12065 -0.2794)
			(stroke
				(width 0.1)
				(type default)
			)
			(layer "F.Fab")
		)
		(fp_line
			(start -0.12065 0.2794)
			(end -0.12065 0.3048)
			(stroke
				(width 0.1)
				(type default)
			)
			(layer "F.Fab")
		)
		(fp_line
			(start -0.12065 0.3048)
			(end -0.67945 0.3048)
			(stroke
				(width 0.1)
				(type default)
			)
			(layer "F.Fab")
		)
		(fp_line
			(start 0.120396 0.2794)
			(end -0.12065 0.2794)
			(stroke
				(width 0.1)
				(type default)
			)
			(layer "F.Fab")
		)
		(fp_line
			(start 0.120396 0.3048)
			(end 0.120396 0.2794)
			(stroke
				(width 0.1)
				(type default)
			)
			(layer "F.Fab")
		)
		(fp_line
			(start 0.12065 -0.3048)
			(end 0.67945 -0.3048)
			(stroke
				(width 0.1)
				(type default)
			)
			(layer "F.Fab")
		)
		(fp_line
			(start 0.12065 -0.2794)
			(end 0.12065 -0.3048)
			(stroke
				(width 0.1)
				(type default)
			)
			(layer "F.Fab")
		)
		(fp_line
			(start 0.67945 -0.3048)
			(end 0.67945 0.3048)
			(stroke
				(width 0.1)
				(type default)
			)
			(layer "F.Fab")
		)
		(fp_line
			(start 0.67945 0.3048)
			(end 0.120396 0.3048)
			(stroke
				(width 0.1)
				(type default)
			)
			(layer "F.Fab")
		)
		(pad "1" smd circle
			(at -0.40005 0)
			(size 0 0)
			(layers "F.Cu" "F.Mask" "F.Paste")
			(net "SMB_BIC_I2C9_MUX0_SSD1_R_SCL")
		)
		(pad "2" smd circle
			(at 0.40005 0)
			(size 0 0)
			(layers "F.Cu" "F.Mask" "F.Paste")
			(net "SMB_BIC_I2C9_MUX0_SSD1_SCL")
		)
	)
	(footprint ""
		(layer "F.Cu")
		(at 231.686862 -139.026392 180)
		(property "Reference" "C2792"
			(at 0 0 180)
			(layer "F.SilkS")
			(hide yes)
			(effects
				(font
					(size 1.27 1.27)
				)
			)
		)
		(property "Value" ""
			(at 0 0 180)
			(layer "F.Fab")
			(effects
				(font
					(size 1.27 1.27)
				)
			)
		)
		(duplicate_pad_numbers_are_jumpers no)
		(fp_line
			(start 0.7874 0.4064)
			(end -0.7874 0.4064)
			(stroke
				(width 0.1524)
				(type default)
			)
			(layer "F.SilkS")
		)
		(fp_line
			(start 0.7874 -0.4064)
			(end 0.7874 0.4064)
			(stroke
				(width 0.1524)
				(type default)
			)
			(layer "F.SilkS")
		)
		(fp_line
			(start -0.7874 0.4064)
			(end -0.7874 -0.4064)
			(stroke
				(width 0.1524)
				(type default)
			)
			(layer "F.SilkS")
		)
		(fp_line
			(start -0.7874 -0.4064)
			(end 0.7874 -0.4064)
			(stroke
				(width 0.1524)
				(type default)
			)
			(layer "F.SilkS")
		)
		(fp_line
			(start 0.67945 0.3048)
			(end 0.120396 0.3048)
			(stroke
				(width 0.1)
				(type default)
			)
			(layer "F.Fab")
		)
		(fp_line
			(start 0.67945 -0.3048)
			(end 0.67945 0.3048)
			(stroke
				(width 0.1)
				(type default)
			)
			(layer "F.Fab")
		)
		(fp_line
			(start 0.12065 -0.2794)
			(end 0.12065 -0.3048)
			(stroke
				(width 0.1)
				(type default)
			)
			(layer "F.Fab")
		)
		(fp_line
			(start 0.12065 -0.3048)
			(end 0.67945 -0.3048)
			(stroke
				(width 0.1)
				(type default)
			)
			(layer "F.Fab")
		)
		(fp_line
			(start 0.120396 0.3048)
			(end 0.120396 0.2794)
			(stroke
				(width 0.1)
				(type default)
			)
			(layer "F.Fab")
		)
		(fp_line
			(start 0.120396 0.2794)
			(end -0.12065 0.2794)
			(stroke
				(width 0.1)
				(type default)
			)
			(layer "F.Fab")
		)
		(fp_line
			(start -0.12065 0.3048)
			(end -0.67945 0.3048)
			(stroke
				(width 0.1)
				(type default)
			)
			(layer "F.Fab")
		)
		(fp_line
			(start -0.12065 0.2794)
			(end -0.12065 0.3048)
			(stroke
				(width 0.1)
				(type default)
			)
			(layer "F.Fab")
		)
		(fp_line
			(start -0.12065 -0.2794)
			(end 0.12065 -0.2794)
			(stroke
				(width 0.1)
				(type default)
			)
			(layer "F.Fab")
		)
		(fp_line
			(start -0.12065 -0.305054)
			(end -0.12065 -0.2794)
			(stroke
				(width 0.1)
				(type default)
			)
			(layer "F.Fab")
		)
		(fp_line
			(start -0.67945 0.3048)
			(end -0.67945 -0.305054)
			(stroke
				(width 0.1)
				(type default)
			)
			(layer "F.Fab")
		)
		(fp_line
			(start -0.67945 -0.305054)
			(end -0.12065 -0.305054)
			(stroke
				(width 0.1)
				(type default)
			)
			(layer "F.Fab")
		)
		(pad "1" smd circle
			(at -0.40005 0 180)
			(size 0 0)
			(layers "F.Cu" "F.Mask" "F.Paste")
			(net "XTAL_CK440_PEX_25M_XOUT")
		)
		(pad "2" smd circle
			(at 0.40005 0 180)
			(size 0 0)
			(layers "F.Cu" "F.Mask" "F.Paste")
			(net "GND")
		)
	)
	(footprint ""
		(layer "F.Cu")
		(at 232.409746 -120.762268 180)
		(property "Reference" "PR6892"
			(at 0 0 180)
			(layer "F.SilkS")
			(hide yes)
			(effects
				(font
					(size 1.27 1.27)
				)
			)
		)
		(property "Value" ""
			(at 0 0 180)
			(layer "F.Fab")
			(effects
				(font
					(size 1.27 1.27)
				)
			)
		)
		(duplicate_pad_numbers_are_jumpers no)
		(fp_line
			(start 0.7874 0.4064)
			(end -0.7874 0.4064)
			(stroke
				(width 0.1524)
				(type default)
			)
			(layer "F.SilkS")
		)
		(fp_line
			(start 0.7874 -0.4064)
			(end 0.7874 0.4064)
			(stroke
				(width 0.1524)
				(type default)
			)
			(layer "F.SilkS")
		)
		(fp_line
			(start -0.7874 0.4064)
			(end -0.7874 -0.4064)
			(stroke
				(width 0.1524)
				(type default)
			)
			(layer "F.SilkS")
		)
		(fp_line
			(start -0.7874 -0.4064)
			(end 0.7874 -0.4064)
			(stroke
				(width 0.1524)
				(type default)
			)
			(layer "F.SilkS")
		)
		(fp_line
			(start 0.67945 0.3048)
			(end 0.120396 0.3048)
			(stroke
				(width 0.1)
				(type default)
			)
			(layer "F.Fab")
		)
		(fp_line
			(start 0.67945 -0.3048)
			(end 0.67945 0.3048)
			(stroke
				(width 0.1)
				(type default)
			)
			(layer "F.Fab")
		)
		(fp_line
			(start 0.12065 -0.2794)
			(end 0.12065 -0.3048)
			(stroke
				(width 0.1)
				(type default)
			)
			(layer "F.Fab")
		)
		(fp_line
			(start 0.12065 -0.3048)
			(end 0.67945 -0.3048)
			(stroke
				(width 0.1)
				(type default)
			)
			(layer "F.Fab")
		)
		(fp_line
			(start 0.120396 0.3048)
			(end 0.120396 0.2794)
			(stroke
				(width 0.1)
				(type default)
			)
			(layer "F.Fab")
		)
		(fp_line
			(start 0.120396 0.2794)
			(end -0.12065 0.2794)
			(stroke
				(width 0.1)
				(type default)
			)
			(layer "F.Fab")
		)
		(fp_line
			(start -0.12065 0.3048)
			(end -0.67945 0.3048)
			(stroke
				(width 0.1)
				(type default)
			)
			(layer "F.Fab")
		)
		(fp_line
			(start -0.12065 0.2794)
			(end -0.12065 0.3048)
			(stroke
				(width 0.1)
				(type default)
			)
			(layer "F.Fab")
		)
		(fp_line
			(start -0.12065 -0.2794)
			(end 0.12065 -0.2794)
			(stroke
				(width 0.1)
				(type default)
			)
			(layer "F.Fab")
		)
		(fp_line
			(start -0.12065 -0.305054)
			(end -0.12065 -0.2794)
			(stroke
				(width 0.1)
				(type default)
			)
			(layer "F.Fab")
		)
		(fp_line
			(start -0.67945 0.3048)
			(end -0.67945 -0.305054)
			(stroke
				(width 0.1)
				(type default)
			)
			(layer "F.Fab")
		)
		(fp_line
			(start -0.67945 -0.305054)
			(end -0.12065 -0.305054)
			(stroke
				(width 0.1)
				(type default)
			)
			(layer "F.Fab")
		)
		(pad "1" smd circle
			(at -0.40005 0 180)
			(size 0 0)
			(layers "F.Cu" "F.Mask" "F.Paste")
			(net "P12V_NIC3_CO_OV_FB")
		)
		(pad "2" smd circle
			(at 0.40005 0 180)
			(size 0 0)
			(layers "F.Cu" "F.Mask" "F.Paste")
			(net "P12V_AUX")
		)
	)
	(footprint ""
		(layer "F.Cu")
		(at 275.822664 -22.867366 90)
		(property "Reference" "C3940"
			(at 0 0 90)
			(layer "F.SilkS")
			(hide yes)
			(effects
				(font
					(size 1.27 1.27)
				)
			)
		)
		(property "Value" ""
			(at 0 0 90)
			(layer "F.Fab")
			(effects
				(font
					(size 1.27 1.27)
				)
			)
		)
		(duplicate_pad_numbers_are_jumpers no)
		(fp_line
			(start 0.7874 -0.4064)
			(end 0.7874 0.4064)
			(stroke
				(width 0.1524)
				(type default)
			)
			(layer "F.SilkS")
		)
		(fp_line
			(start -0.7874 -0.4064)
			(end 0.7874 -0.4064)
			(stroke
				(width 0.1524)
				(type default)
			)
			(layer "F.SilkS")
		)
		(fp_line
			(start 0.7874 0.4064)
			(end -0.7874 0.4064)
			(stroke
				(width 0.1524)
				(type default)
			)
			(layer "F.SilkS")
		)
		(fp_line
			(start -0.7874 0.4064)
			(end -0.7874 -0.4064)
			(stroke
				(width 0.1524)
				(type default)
			)
			(layer "F.SilkS")
		)
		(fp_line
			(start -0.12065 -0.305054)
			(end -0.12065 -0.2794)
			(stroke
				(width 0.1)
				(type default)
			)
			(layer "F.Fab")
		)
		(fp_line
			(start -0.67945 -0.305054)
			(end -0.12065 -0.305054)
			(stroke
				(width 0.1)
				(type default)
			)
			(layer "F.Fab")
		)
		(fp_line
			(start 0.67945 -0.3048)
			(end 0.67945 0.3048)
			(stroke
				(width 0.1)
				(type default)
			)
			(layer "F.Fab")
		)
		(fp_line
			(start 0.12065 -0.3048)
			(end 0.67945 -0.3048)
			(stroke
				(width 0.1)
				(type default)
			)
			(layer "F.Fab")
		)
		(fp_line
			(start 0.12065 -0.2794)
			(end 0.12065 -0.3048)
			(stroke
				(width 0.1)
				(type default)
			)
			(layer "F.Fab")
		)
		(fp_line
			(start -0.12065 -0.2794)
			(end 0.12065 -0.2794)
			(stroke
				(width 0.1)
				(type default)
			)
			(layer "F.Fab")
		)
		(fp_line
			(start 0.120396 0.2794)
			(end -0.12065 0.2794)
			(stroke
				(width 0.1)
				(type default)
			)
			(layer "F.Fab")
		)
		(fp_line
			(start -0.12065 0.2794)
			(end -0.12065 0.3048)
			(stroke
				(width 0.1)
				(type default)
			)
			(layer "F.Fab")
		)
		(fp_line
			(start 0.67945 0.3048)
			(end 0.120396 0.3048)
			(stroke
				(width 0.1)
				(type default)
			)
			(layer "F.Fab")
		)
		(fp_line
			(start 0.120396 0.3048)
			(end 0.120396 0.2794)
			(stroke
				(width 0.1)
				(type default)
			)
			(layer "F.Fab")
		)
		(fp_line
			(start -0.12065 0.3048)
			(end -0.67945 0.3048)
			(stroke
				(width 0.1)
				(type default)
			)
			(layer "F.Fab")
		)
		(fp_line
			(start -0.67945 0.3048)
			(end -0.67945 -0.305054)
			(stroke
				(width 0.1)
				(type default)
			)
			(layer "F.Fab")
		)
		(pad "1" smd circle
			(at -0.40005 0 90)
			(size 0 0)
			(layers "F.Cu" "F.Mask" "F.Paste")
			(net "P12V_SSD9")
		)
		(pad "2" smd circle
			(at 0.40005 0 90)
			(size 0 0)
			(layers "F.Cu" "F.Mask" "F.Paste")
			(net "GND")
		)
	)
)
